(kicad_pcb
	(version 20260206)
	(generator "pcbnew")
	(generator_version "10.0")
	(general
		(thickness 1.21888)
		(legacy_teardrops no)
	)
	(paper "A4")
	(title_block
		(title "timecard-v8 — TimeCard-DC-V8_EXP.PcbDoc")
		(comment 1 "Time Appliance Project (Time Card) / footprints 236-244 of 288")
	)
	(layers
		(0 "F.Cu" signal "TOP")
		(4 "In1.Cu" signal "SGND")
		(6 "In2.Cu" signal "IN1")
		(8 "In3.Cu" signal "IN2")
		(10 "In4.Cu" signal "SGND1")
		(2 "B.Cu" signal "BOTTOM")
		(9 "F.Adhes" user "F.Adhesive")
		(11 "B.Adhes" user "B.Adhesive")
		(13 "F.Paste" user "Top Paste")
		(15 "B.Paste" user "Bottom Paste")
		(5 "F.SilkS" user "Top Overlay")
		(7 "B.SilkS" user "Bottom Overlay")
		(1 "F.Mask" user "Top Solder")
		(3 "B.Mask" user "Bottom Solder")
		(17 "Dwgs.User" user "User.Drawings")
		(19 "Cmts.User" user "User.Comments")
		(21 "Eco1.User" user "User.Eco1")
		(23 "Eco2.User" user "User.Eco2")
		(25 "Edge.Cuts" user)
		(27 "Margin" user)
		(31 "F.CrtYd" user "Top Courtyard")
		(29 "B.CrtYd" user "Bottom Courtyard")
		(35 "F.Fab" user "Top Component Center")
		(33 "B.Fab" user "Bottom Component Center")
	)
	(footprint "Vault:FP-0402-L_1_0_0_05-W_0_5-IPC_A"
		(layer "F.Cu")
		(at 205.7261 111.4162 180)
		(property "Reference" "C4"
			(at 0.6 -3.393345 0)
			(unlocked yes)
			(layer "F.SilkS")
			(effects
				(font
					(size 0.762 0.762)
					(thickness 0.2286)
				)
				(justify left bottom)
			)
		)
		(property "Value" "1uF_16V_0402"
			(at -8.7497 -4.622845 0)
			(unlocked yes)
			(layer "F.SilkS")
			(hide yes)
			(effects
				(font
					(size 0.762 0.762)
					(thickness 0.2286)
				)
				(justify left bottom)
			)
		)
		(sheetname "POWER")
		(sheetfile "POWER.kicad_sch")
		(duplicate_pad_numbers_are_jumpers no)
		(fp_line
			(start 0.83623 0.73624)
			(end -0.83624 0.73624)
			(stroke
				(width 0.2)
				(type solid)
			)
			(layer "F.SilkS")
		)
		(fp_line
			(start 0.83623 -0.73624)
			(end -0.83624 -0.73624)
			(stroke
				(width 0.2)
				(type solid)
			)
			(layer "F.SilkS")
		)
		(fp_line
			(start 1.03623 0.53624)
			(end -1.03624 0.53624)
			(stroke
				(width 0.2)
				(type solid)
			)
			(layer "F.CrtYd")
		)
		(fp_line
			(start 1.03623 -0.53624)
			(end 1.03623 0.53624)
			(stroke
				(width 0.2)
				(type solid)
			)
			(layer "F.CrtYd")
		)
		(fp_line
			(start 1.03623 -0.53624)
			(end -1.03624 -0.53624)
			(stroke
				(width 0.2)
				(type solid)
			)
			(layer "F.CrtYd")
		)
		(fp_line
			(start -1.03624 -0.53624)
			(end -1.03624 0.53624)
			(stroke
				(width 0.2)
				(type solid)
			)
			(layer "F.CrtYd")
		)
		(fp_line
			(start 1.03623 0.53624)
			(end -1.03624 0.53624)
			(stroke
				(width 0.2)
				(type solid)
			)
			(layer "F.Fab")
		)
		(fp_line
			(start 1.03623 -0.53624)
			(end 1.03623 0.53624)
			(stroke
				(width 0.2)
				(type solid)
			)
			(layer "F.Fab")
		)
		(fp_line
			(start 1.03623 -0.53624)
			(end -1.03624 -0.53624)
			(stroke
				(width 0.2)
				(type solid)
			)
			(layer "F.Fab")
		)
		(fp_line
			(start 0.5 0)
			(end -0.5 0)
			(stroke
				(width 0.1)
				(type solid)
			)
			(layer "F.Fab")
		)
		(fp_line
			(start 0 -0.5)
			(end 0 0.5)
			(stroke
				(width 0.1)
				(type solid)
			)
			(layer "F.Fab")
		)
		(fp_line
			(start -1.03624 -0.53624)
			(end -1.03624 0.53624)
			(stroke
				(width 0.2)
				(type solid)
			)
			(layer "F.Fab")
		)
		(fp_text user "${REFERENCE}"
			(at -0.00002 0.09601 180)
			(unlocked yes)
			(layer "F.Fab")
			(effects
				(font
					(face "Arial")
					(size 0.63 0.63)
					(thickness 0.1)
				)
				(justify left bottom)
			)
		)
		(pad "1" smd rect
			(at -0.47856 0 180)
			(size 0.71535 0.67248)
			(layers "F.Cu" "F.Mask" "F.Paste")
			(net "P5V_VDD")
			(solder_mask_margin 0)
			(solder_paste_margin 0)
		)
		(pad "2" smd rect
			(at 0.47856 0 180)
			(size 0.71535 0.67248)
			(layers "F.Cu" "F.Mask" "F.Paste")
			(net "GND")
			(solder_mask_margin 0)
			(solder_paste_margin 0)
		)
	)
	(footprint "Vault:AMPH-901-143-6RFX_V"
		(layer "F.Cu")
		(at 60.9761 135.5786 180)
		(property "Reference" "AN4"
			(at -5.817355 2.786 90)
			(unlocked yes)
			(layer "F.SilkS")
			(effects
				(font
					(size 0.762 0.762)
					(thickness 0.2286)
				)
				(justify left bottom)
			)
		)
		(property "Value" "RF2-49B-T-00-50-G-HDW"
			(at 4.6101 -12.120245 0)
			(unlocked yes)
			(layer "F.SilkS")
			(hide yes)
			(effects
				(font
					(size 0.762 0.762)
					(thickness 0.2286)
				)
				(justify left bottom)
			)
		)
		(sheetname "USER_IO")
		(sheetfile "USER_IO.kicad_sch")
		(duplicate_pad_numbers_are_jumpers no)
		(fp_line
			(start 3.5 -1.38)
			(end 3.5 1.38)
			(stroke
				(width 0.2)
				(type solid)
			)
			(layer "F.SilkS")
		)
		(fp_line
			(start 1.38 3.5)
			(end -1.38 3.5)
			(stroke
				(width 0.2)
				(type solid)
			)
			(layer "F.SilkS")
		)
		(fp_line
			(start 1.38 -3.5)
			(end -1.38 -3.5)
			(stroke
				(width 0.2)
				(type solid)
			)
			(layer "F.SilkS")
		)
		(fp_line
			(start -3.5 -1.38)
			(end -3.5 1.38)
			(stroke
				(width 0.2)
				(type solid)
			)
			(layer "F.SilkS")
		)
		(pad "1" thru_hole rect
			(at 0 0 180)
			(size 2 2)
			(drill 1.5)
			(layers "*.Cu" "*.Mask")
			(remove_unused_layers no)
			(net "NetAN4_1")
		)
		(pad "2" thru_hole circle
			(at -2.54 -2.54 180)
			(size 2.2 2.2)
			(drill 1.7)
			(layers "*.Cu" "*.Mask")
			(remove_unused_layers no)
			(net "GND")
			(thermal_bridge_angle 90)
		)
		(pad "3" thru_hole circle
			(at -2.54 2.54 180)
			(size 2.2 2.2)
			(drill 1.7)
			(layers "*.Cu" "*.Mask")
			(remove_unused_layers no)
			(net "GND")
			(thermal_bridge_angle 90)
		)
		(pad "4" thru_hole circle
			(at 2.54 2.54 180)
			(size 2.2 2.2)
			(drill 1.7)
			(layers "*.Cu" "*.Mask")
			(remove_unused_layers no)
			(net "GND")
			(thermal_bridge_angle 90)
		)
		(pad "5" thru_hole circle
			(at 2.54 -2.54 180)
			(size 2.2 2.2)
			(drill 1.7)
			(layers "*.Cu" "*.Mask")
			(remove_unused_layers no)
			(net "GND")
			(thermal_bridge_angle 90)
		)
	)
	(footprint "Vault:RESC1005X40X25NL05T05"
		(layer "F.Cu")
		(at 218.0761 75.9162)
		(property "Reference" "R100"
			(at -0.0214 -1.073069 0)
			(unlocked yes)
			(layer "F.SilkS")
			(effects
				(font
					(size 0.762 0.762)
					(thickness 0.2286)
				)
			)
		)
		(property "Value" "DNI_27_1%_0402"
			(at -2.732281 10.296375 270)
			(unlocked yes)
			(layer "F.SilkS")
			(hide yes)
			(effects
				(font
					(size 0.762 0.762)
					(thickness 0.2286)
				)
			)
		)
		(sheetname "USBUart_DipSelects")
		(sheetfile "USBUart_DipSelects.kicad_sch")
		(duplicate_pad_numbers_are_jumpers no)
		(pad "1" smd rect
			(at -0.45 0 90)
			(size 0.55 0.55)
			(layers "F.Cu" "F.Mask" "F.Paste")
			(net "FTDI_RX")
		)
		(pad "2" smd rect
			(at 0.45 0 90)
			(size 0.55 0.55)
			(layers "F.Cu" "F.Mask" "F.Paste")
			(net "UART1_TXD")
		)
	)
	(footprint "Vault:RESC1005X40X25LL05T10"
		(layer "F.Cu")
		(at 128.0261 84.4162 180)
		(property "Reference" "R98"
			(at -1.0286 2.873069 0)
			(unlocked yes)
			(layer "F.SilkS")
			(effects
				(font
					(size 0.762 0.762)
					(thickness 0.2286)
				)
			)
		)
		(property "Value" "49.9_1%_0402"
			(at -2.579871 8.823665 90)
			(unlocked yes)
			(layer "F.SilkS")
			(hide yes)
			(effects
				(font
					(size 0.762 0.762)
					(thickness 0.2286)
				)
			)
		)
		(sheetname "USBUart_DipSelects")
		(sheetfile "USBUart_DipSelects.kicad_sch")
		(duplicate_pad_numbers_are_jumpers no)
		(pad "1" smd rect
			(at -0.375 0 270)
			(size 0.45 0.5)
			(layers "F.Cu" "F.Mask" "F.Paste")
			(net "MAC_PPS_IN")
		)
		(pad "2" smd rect
			(at 0.375 0 270)
			(size 0.45 0.5)
			(layers "F.Cu" "F.Mask" "F.Paste")
			(net "NetR98_2")
		)
	)
	(footprint "Vault:RESC1608X55X25NL10T15"
		(layer "F.Cu")
		(at 77.8761 108.6162 180)
		(property "Reference" "R33"
			(at -0.2286 1.473069 0)
			(unlocked yes)
			(layer "F.SilkS")
			(effects
				(font
					(size 0.762 0.762)
					(thickness 0.2286)
				)
			)
		)
		(property "Value" "49.9R"
			(at -2.884671 3.186595 90)
			(unlocked yes)
			(layer "F.SilkS")
			(hide yes)
			(effects
				(font
					(size 0.762 0.762)
					(thickness 0.2286)
				)
			)
		)
		(sheetname "USER_IO")
		(sheetfile "USER_IO.kicad_sch")
		(duplicate_pad_numbers_are_jumpers no)
		(pad "1" smd rect
			(at -0.7 0 270)
			(size 0.9 0.7)
			(layers "F.Cu" "F.Mask" "F.Paste")
			(net "NetR33_1")
		)
		(pad "2" smd rect
			(at 0.7 0 270)
			(size 0.9 0.7)
			(layers "F.Cu" "F.Mask" "F.Paste")
			(net "NetAN2_1")
		)
	)
	(footprint "Vault:RESC1005X40X25NL05T10"
		(layer "F.Cu")
		(at 203.5761 121.0662 90)
		(property "Reference" "R76"
			(at 2.3786 -1.523079 90)
			(unlocked yes)
			(layer "F.SilkS")
			(effects
				(font
					(size 0.762 0.762)
					(thickness 0.2286)
				)
			)
		)
		(property "Value" "2.49K_1%_0402"
			(at -2.732271 9.53462 0)
			(unlocked yes)
			(layer "F.SilkS")
			(hide yes)
			(effects
				(font
					(size 0.762 0.762)
					(thickness 0.2286)
				)
			)
		)
		(sheetname "POWER")
		(sheetfile "POWER.kicad_sch")
		(duplicate_pad_numbers_are_jumpers no)
		(pad "1" smd rect
			(at -0.425 0 180)
			(size 0.55 0.6)
			(layers "F.Cu" "F.Mask" "F.Paste")
			(net "P3V3_FB")
		)
		(pad "2" smd rect
			(at 0.425 0 180)
			(size 0.55 0.6)
			(layers "F.Cu" "F.Mask" "F.Paste")
			(net "P3V3_SENSE")
		)
	)
	(footprint "Vault:RESC1005X40X25NL05T05"
		(layer "F.Cu")
		(at 217.2261 79.3162)
		(property "Reference" "R87"
			(at 0.0286 -0.673069 0)
			(unlocked yes)
			(layer "F.SilkS")
			(effects
				(font
					(size 0.762 0.762)
					(thickness 0.2286)
				)
			)
		)
		(property "Value" "27_1%_0402"
			(at -2.732281 7.37632 270)
			(unlocked yes)
			(layer "F.SilkS")
			(hide yes)
			(effects
				(font
					(size 0.762 0.762)
					(thickness 0.2286)
				)
			)
		)
		(sheetname "USBUart_DipSelects")
		(sheetfile "USBUart_DipSelects.kicad_sch")
		(duplicate_pad_numbers_are_jumpers no)
		(pad "1" smd rect
			(at -0.45 0 90)
			(size 0.55 0.55)
			(layers "F.Cu" "F.Mask" "F.Paste")
			(net "FTDI_TX")
		)
		(pad "2" smd rect
			(at 0.45 0 90)
			(size 0.55 0.55)
			(layers "F.Cu" "F.Mask" "F.Paste")
			(net "NetR87_2")
		)
	)
	(footprint "Vault:FP-T495D107K016ATE125-MFG"
		(layer "F.Cu")
		(at 230.8261 101.7162 -90)
		(property "Reference" "C14"
			(at -1.97531 -1.604455 90)
			(unlocked yes)
			(layer "F.SilkS")
			(effects
				(font
					(size 0.762 0.762)
					(thickness 0.2286)
				)
				(justify left bottom)
			)
		)
		(property "Value" "100uF_16V_2917"
			(at 15.597845 -5.1281 0)
			(unlocked yes)
			(layer "F.SilkS")
			(hide yes)
			(effects
				(font
					(size 0.762 0.762)
					(thickness 0.2286)
				)
				(justify left bottom)
			)
		)
		(sheetname "POWER")
		(sheetfile "POWER.kicad_sch")
		(duplicate_pad_numbers_are_jumpers no)
		(fp_line
			(start -3.8 2.3)
			(end -3.8 1.54)
			(stroke
				(width 0.2)
				(type solid)
			)
			(layer "F.SilkS")
		)
		(fp_line
			(start 3.8 2.3)
			(end -3.8 2.3)
			(stroke
				(width 0.2)
				(type solid)
			)
			(layer "F.SilkS")
		)
		(fp_line
			(start 3.8 2.3)
			(end 3.8 1.54)
			(stroke
				(width 0.2)
				(type solid)
			)
			(layer "F.SilkS")
		)
		(fp_line
			(start 4.7 0.3)
			(end 4.7 -0.3)
			(stroke
				(width 0.2)
				(type solid)
			)
			(layer "F.SilkS")
		)
		(fp_line
			(start 5 0)
			(end 4.4 0)
			(stroke
				(width 0.2)
				(type solid)
			)
			(layer "F.SilkS")
		)
		(fp_line
			(start -3.8 -1.54)
			(end -3.8 -2.3)
			(stroke
				(width 0.2)
				(type solid)
			)
			(layer "F.SilkS")
		)
		(fp_line
			(start 3.8 -1.54)
			(end 3.8 -2.3)
			(stroke
				(width 0.2)
				(type solid)
			)
			(layer "F.SilkS")
		)
		(fp_line
			(start 3.8 -2.3)
			(end -3.8 -2.3)
			(stroke
				(width 0.2)
				(type solid)
			)
			(layer "F.SilkS")
		)
		(fp_line
			(start -4.105 2.4)
			(end -4.105 -2.4)
			(stroke
				(width 0.2)
				(type solid)
			)
			(layer "F.CrtYd")
		)
		(fp_line
			(start 4.105 2.4)
			(end -4.105 2.4)
			(stroke
				(width 0.2)
				(type solid)
			)
			(layer "F.CrtYd")
		)
		(fp_line
			(start 4.105 2.4)
			(end 4.105 -2.4)
			(stroke
				(width 0.2)
				(type solid)
			)
			(layer "F.CrtYd")
		)
		(fp_line
			(start 4.105 -2.4)
			(end -4.105 -2.4)
			(stroke
				(width 0.2)
				(type solid)
			)
			(layer "F.CrtYd")
		)
		(fp_line
			(start -4.105 2.4)
			(end -4.105 -2.4)
			(stroke
				(width 0.2)
				(type solid)
			)
			(layer "F.Fab")
		)
		(fp_line
			(start 4.105 2.4)
			(end -4.105 2.4)
			(stroke
				(width 0.2)
				(type solid)
			)
			(layer "F.Fab")
		)
		(fp_line
			(start 4.105 2.4)
			(end 4.105 -2.4)
			(stroke
				(width 0.2)
				(type solid)
			)
			(layer "F.Fab")
		)
		(fp_line
			(start 0 0.5)
			(end 0 -0.5)
			(stroke
				(width 0.1)
				(type solid)
			)
			(layer "F.Fab")
		)
		(fp_line
			(start 0.5 0)
			(end -0.5 0)
			(stroke
				(width 0.1)
				(type solid)
			)
			(layer "F.Fab")
		)
		(fp_line
			(start 4.105 -2.4)
			(end -4.105 -2.4)
			(stroke
				(width 0.2)
				(type solid)
			)
			(layer "F.Fab")
		)
		(fp_text user "${REFERENCE}"
			(at 0.00001 0.28425 270)
			(unlocked yes)
			(layer "F.Fab")
			(effects
				(font
					(face "Arial")
					(size 0.63 0.63)
					(thickness 0.1)
				)
				(justify left bottom)
			)
		)
		(pad "1" smd rect
			(at -3.01 0 270)
			(size 1.99 2.33)
			(layers "F.Cu" "F.Mask" "F.Paste")
			(net "GND")
			(solder_mask_margin 0)
			(solder_paste_margin 0)
		)
		(pad "2" smd rect
			(at 3.01 0 270)
			(size 1.99 2.33)
			(layers "F.Cu" "F.Mask" "F.Paste")
			(net "+5.0V")
			(solder_mask_margin 0)
			(solder_paste_margin 0)
		)
	)
	(footprint "GNSS:GNSS"
		(locked yes)
		(layer "F.Cu")
		(at 225.8486 61.6786 180)
		(property "Reference" "U15"
			(at 61.995579 -17.309 90)
			(unlocked yes)
			(layer "F.SilkS")
			(effects
				(font
					(size 0.762 0.762)
					(thickness 0.2286)
				)
			)
		)
		(property "Value" "RCB-F9T-1"
			(at -7.786881 -13.756155 90)
			(unlocked yes)
			(layer "F.SilkS")
			(hide yes)
			(effects
				(font
					(size 0.762 0.762)
					(thickness 0.2286)
				)
			)
		)
		(sheetname "GPS_IMU_SENSORS")
		(sheetfile "GPS_IMU_SENSORS.kicad_sch")
		(duplicate_pad_numbers_are_jumpers no)
		(fp_line
			(start 61.07 11.28)
			(end -6.11 11.28)
			(stroke
				(width 0.254)
				(type solid)
			)
			(layer "F.SilkS")
		)
		(fp_line
			(start 61.07 -20.47)
			(end 61.07 11.28)
			(stroke
				(width 0.254)
				(type solid)
			)
			(layer "F.SilkS")
		)
		(fp_line
			(start 61.07 -20.47)
			(end -6.11 -20.47)
			(stroke
				(width 0.254)
				(type solid)
			)
			(layer "F.SilkS")
		)
		(fp_line
			(start -6.11 -20.47)
			(end -6.11 11.28)
			(stroke
				(width 0.254)
				(type solid)
			)
			(layer "F.SilkS")
		)
		(pad "0" thru_hole circle
			(at 0 -2 90)
			(size 0 0)
			(drill 0.76)
			(layers "*.Cu" "*.Mask")
			(remove_unused_layers no)
			(thermal_bridge_angle 90)
		)
		(pad "0" thru_hole circle
			(at 0 2 90)
			(size 0 0)
			(drill 0.76)
			(layers "*.Cu" "*.Mask")
			(remove_unused_layers no)
			(thermal_bridge_angle 90)
		)
		(pad "1" smd rect
			(at -2.2225 3 90)
			(size 1.12 2.105)
			(layers "F.Cu" "F.Mask" "F.Paste")
			(net "+5.0V")
		)
		(pad "2" smd rect
			(at 2.2225 3 90)
			(size 1.12 2.105)
			(layers "F.Cu" "F.Mask" "F.Paste")
			(net "+3.3V")
		)
		(pad "3" smd rect
			(at -2.2225 1 90)
			(size 1.12 2.105)
			(layers "F.Cu" "F.Mask" "F.Paste")
			(net "GPS2_TX")
		)
		(pad "4" smd rect
			(at 2.2225 1 90)
			(size 1.12 2.105)
			(layers "F.Cu" "F.Mask" "F.Paste")
			(net "GPS2_RST")
		)
		(pad "5" smd rect
			(at -2.2225 -1 90)
			(size 1.12 2.105)
			(layers "F.Cu" "F.Mask" "F.Paste")
			(net "GPS2_RX")
		)
		(pad "6" smd rect
			(at 2.2225 -1 90)
			(size 1.12 2.105)
			(layers "F.Cu" "F.Mask" "F.Paste")
			(net "GPS2_TP1")
		)
		(pad "7" smd rect
			(at -2.2225 -3 90)
			(size 1.12 2.105)
			(layers "F.Cu" "F.Mask" "F.Paste")
			(net "GPS2_TP2")
		)
		(pad "8" smd rect
			(at 2.2225 -3 90)
			(size 1.12 2.105)
			(layers "F.Cu" "F.Mask" "F.Paste")
			(net "GND")
		)
	)
)
